(kicad_pcb
	(version 20240108)
	(generator "pcbnew")
	(generator_version "8.0")
	(general
		(thickness 1.62)
		(legacy_teardrops no)
	)
	(paper "A4")
	(title_block
		(title "Jetson Orin Baseboard")
		(date "2025-03-12")
		(rev "1.3.4")
		(company "Antmicro Ltd")
		(comment 1 "www.antmicro.com")
		(comment 9 "footprints 182-186 of 677")
	)
	(layers
		(0 "F.Cu" signal)
		(1 "In1.Cu" signal)
		(2 "In2.Cu" signal)
		(3 "In3.Cu" signal)
		(4 "In4.Cu" jumper)
		(5 "In5.Cu" signal)
		(6 "In6.Cu" signal)
		(31 "B.Cu" signal)
		(32 "B.Adhes" user "B.Adhesive")
		(33 "F.Adhes" user "F.Adhesive")
		(34 "B.Paste" user)
		(35 "F.Paste" user)
		(36 "B.SilkS" user "B.Silkscreen")
		(37 "F.SilkS" user "F.Silkscreen")
		(38 "B.Mask" user)
		(39 "F.Mask" user)
		(40 "Dwgs.User" user "User.Drawings")
		(41 "Cmts.User" user "User.Comments")
		(42 "Eco1.User" user "User.Eco1")
		(43 "Eco2.User" user "User.Eco2")
		(44 "Edge.Cuts" user)
		(45 "Margin" user)
		(46 "B.CrtYd" user "B.Courtyard")
		(47 "F.CrtYd" user "F.Courtyard")
		(48 "B.Fab" user)
		(49 "F.Fab" user)
	)
	(footprint "antmicro-footprints:R_0402_1005Metric"
		(layer "F.Cu")
		(at 87.05 114.2 -90)
		(descr "Resistor SMD 0402")
		(tags "resistor SMD 0402")
		(property "Reference" "R293"
			(at -0.84 -0.41 -90)
			(layer "F.SilkS")
			(effects
				(font
					(size 0.7 0.7)
					(thickness 0.15)
				)
				(justify left bottom)
			)
		)
		(property "Value" "R_0R_0402"
			(at 0 1.4 -90)
			(layer "F.Fab")
			(effects
				(font
					(size 0.7 0.7)
					(thickness 0.15)
				)
				(justify left bottom)
			)
		)
		(property "Footprint" "antmicro-footprints:R_0402_1005Metric"
			(at 0 0 -90)
			(layer "F.Fab")
			(hide yes)
			(effects
				(font
					(size 1.27 1.27)
					(thickness 0.15)
				)
			)
		)
		(property "Datasheet" "https://industrial.panasonic.com/cdbs/www-data/pdf/RDA0000/AOA0000C301.pdf"
			(at 0 0 -90)
			(layer "F.Fab")
			(hide yes)
			(effects
				(font
					(size 1.27 1.27)
					(thickness 0.15)
				)
			)
		)
		(property "Author" "Antmicro"
			(at -27.15 201.25 0)
			(layer "F.Fab")
			(hide yes)
			(effects
				(font
					(size 1 1)
					(thickness 0.15)
				)
			)
		)
		(property "Current" "1A"
			(at -27.15 201.25 0)
			(layer "F.Fab")
			(hide yes)
			(effects
				(font
					(size 1 1)
					(thickness 0.15)
				)
			)
		)
		(property "License" "Apache-2.0"
			(at -27.15 201.25 0)
			(layer "F.Fab")
			(hide yes)
			(effects
				(font
					(size 1 1)
					(thickness 0.15)
				)
			)
		)
		(property "MPN" "ERJ2GE0R00X"
			(at -27.15 201.25 0)
			(layer "F.Fab")
			(hide yes)
			(effects
				(font
					(size 1 1)
					(thickness 0.15)
				)
			)
		)
		(property "Manufacturer" "Panasonic"
			(at -27.15 201.25 0)
			(layer "F.Fab")
			(hide yes)
			(effects
				(font
					(size 1 1)
					(thickness 0.15)
				)
			)
		)
		(property "Tolerance" ""
			(at -27.15 201.25 0)
			(layer "F.Fab")
			(hide yes)
			(effects
				(font
					(size 1 1)
					(thickness 0.15)
				)
			)
		)
		(property "Val" "0R"
			(at -27.15 201.25 0)
			(layer "F.Fab")
			(hide yes)
			(effects
				(font
					(size 1 1)
					(thickness 0.15)
				)
			)
		)
		(sheetname "HDMI")
		(sheetfile "hdmi.kicad_sch")
		(attr smd exclude_from_pos_files exclude_from_bom dnp)
		(fp_rect
			(start -0.925 -0.47)
			(end 0.925 0.47)
			(stroke
				(width 0.05)
				(type default)
			)
			(fill none)
			(layer "F.CrtYd")
		)
		(fp_rect
			(start -0.5 -0.25)
			(end 0.5 0.25)
			(stroke
				(width 0.15)
				(type solid)
			)
			(fill none)
			(layer "F.Fab")
		)
		(fp_text user "License: Apache-2.0"
			(at -0.95 5.169 -90)
			(layer "F.Fab")
			(hide yes)
			(effects
				(font
					(size 0.7 0.7)
					(thickness 0.15)
				)
				(justify left bottom)
			)
		)
		(fp_text user "Author: Antmicro"
			(at -0.95 4.169 -90)
			(layer "F.Fab")
			(hide yes)
			(effects
				(font
					(size 0.7 0.7)
					(thickness 0.15)
				)
				(justify left bottom)
			)
		)
		(fp_text user "${REFERENCE}"
			(at -0.95 3.168 -90)
			(layer "F.Fab")
			(hide yes)
			(effects
				(font
					(size 0.7 0.7)
					(thickness 0.15)
				)
				(justify left bottom)
			)
		)
		(pad "1" smd roundrect
			(at -0.48 0 270)
			(size 0.59 0.64)
			(layers "F.Cu" "F.Paste" "F.Mask")
			(roundrect_rratio 0.25)
			(net 576 "/HDMI/HDMI_HPD_5V_R")
			(pintype "passive")
		)
		(pad "2" smd roundrect
			(at 0.48 0 270)
			(size 0.59 0.64)
			(layers "F.Cu" "F.Paste" "F.Mask")
			(roundrect_rratio 0.25)
			(net 529 "/HDMI/HDMI_HPD_5V")
			(pintype "passive")
		)
	)
	(footprint "antmicro-footprints:C_0402_1005Metric"
		(layer "F.Cu")
		(at 137.115 109.05)
		(descr "Capacitor SMD 0402")
		(tags "capacitor SMD 0402")
		(property "Reference" "C105"
			(at -3.615 0.45 0)
			(layer "F.SilkS")
			(effects
				(font
					(size 0.7 0.7)
					(thickness 0.15)
				)
				(justify left bottom)
			)
		)
		(property "Value" "C_1u_0402"
			(at 0 1.4 0)
			(layer "F.Fab")
			(effects
				(font
					(size 0.7 0.7)
					(thickness 0.15)
				)
				(justify left bottom)
			)
		)
		(property "Footprint" "antmicro-footprints:C_0402_1005Metric"
			(at 0 0 0)
			(layer "F.Fab")
			(hide yes)
			(effects
				(font
					(size 1.27 1.27)
					(thickness 0.15)
				)
			)
		)
		(property "Datasheet" "https://product.tdk.com/en/search/capacitor/ceramic/mlcc/info?part_no=C1005X6S1A105K050BC"
			(at 0 0 0)
			(layer "F.Fab")
			(hide yes)
			(effects
				(font
					(size 1.27 1.27)
					(thickness 0.15)
				)
			)
		)
		(property "Author" "Antmicro"
			(at 0 0 0)
			(layer "F.Fab")
			(hide yes)
			(effects
				(font
					(size 1 1)
					(thickness 0.15)
				)
			)
		)
		(property "Dielectric" ""
			(at 0 0 0)
			(layer "F.Fab")
			(hide yes)
			(effects
				(font
					(size 1 1)
					(thickness 0.15)
				)
			)
		)
		(property "License" "Apache-2.0"
			(at 0 0 0)
			(layer "F.Fab")
			(hide yes)
			(effects
				(font
					(size 1 1)
					(thickness 0.15)
				)
			)
		)
		(property "MPN" "C1005X6S1A105K050BC"
			(at 0 0 0)
			(layer "F.Fab")
			(hide yes)
			(effects
				(font
					(size 1 1)
					(thickness 0.15)
				)
			)
		)
		(property "Manufacturer" "TDK"
			(at 0 0 0)
			(layer "F.Fab")
			(hide yes)
			(effects
				(font
					(size 1 1)
					(thickness 0.15)
				)
			)
		)
		(property "Val" "1u"
			(at 0 0 0)
			(layer "F.Fab")
			(hide yes)
			(effects
				(font
					(size 1 1)
					(thickness 0.15)
				)
			)
		)
		(property "Voltage" ""
			(at 0 0 0)
			(layer "F.Fab")
			(hide yes)
			(effects
				(font
					(size 1 1)
					(thickness 0.15)
				)
			)
		)
		(sheetname "Peripherals")
		(sheetfile "peripherals.kicad_sch")
		(attr smd)
		(fp_rect
			(start -0.925 -0.47)
			(end 0.925 0.47)
			(stroke
				(width 0.05)
				(type default)
			)
			(fill none)
			(layer "F.CrtYd")
		)
		(fp_line
			(start -0.494 -0.25)
			(end 0.504 -0.25)
			(stroke
				(width 0.15)
				(type solid)
			)
			(layer "F.Fab")
		)
		(fp_line
			(start -0.494 0.248)
			(end -0.494 -0.25)
			(stroke
				(width 0.15)
				(type solid)
			)
			(layer "F.Fab")
		)
		(fp_line
			(start 0.504 -0.25)
			(end 0.504 0.248)
			(stroke
				(width 0.15)
				(type solid)
			)
			(layer "F.Fab")
		)
		(fp_line
			(start 0.504 0.248)
			(end -0.494 0.248)
			(stroke
				(width 0.15)
				(type solid)
			)
			(layer "F.Fab")
		)
		(fp_text user "License: Apache-2.0"
			(at -0.932 5.17 0)
			(layer "F.Fab")
			(hide yes)
			(effects
				(font
					(size 0.7 0.7)
					(thickness 0.15)
				)
				(justify left bottom)
			)
		)
		(fp_text user "${REFERENCE}"
			(at -0.932 3.168 0)
			(layer "F.Fab")
			(hide yes)
			(effects
				(font
					(size 0.7 0.7)
					(thickness 0.15)
				)
				(justify left bottom)
			)
		)
		(fp_text user "Author: Antmicro"
			(at -0.932 4.17 0)
			(layer "F.Fab")
			(hide yes)
			(effects
				(font
					(size 0.7 0.7)
					(thickness 0.15)
				)
				(justify left bottom)
			)
		)
		(pad "1" smd roundrect
			(at -0.48 0)
			(size 0.59 0.64)
			(layers "F.Cu" "F.Paste" "F.Mask")
			(roundrect_rratio 0.25)
			(net 1 "GND")
			(pintype "passive")
		)
		(pad "2" smd roundrect
			(at 0.48 0)
			(size 0.59 0.64)
			(layers "F.Cu" "F.Paste" "F.Mask")
			(roundrect_rratio 0.25)
			(net 482 "/Peripherals/3V3_CONN")
			(pintype "passive")
		)
	)
	(footprint "antmicro-footprints:R_0402_1005Metric"
		(layer "F.Cu")
		(at 67.67 99.42 90)
		(descr "Resistor SMD 0402")
		(tags "resistor SMD 0402")
		(property "Reference" "R169"
			(at -3.605 0.555 90)
			(layer "F.SilkS")
			(effects
				(font
					(size 0.7 0.7)
					(thickness 0.15)
				)
				(justify left bottom)
			)
		)
		(property "Value" "R_2k7_0402"
			(at -1.011843 1.772047 90)
			(layer "F.Fab")
			(effects
				(font
					(size 0.7 0.7)
					(thickness 0.15)
				)
				(justify left bottom)
			)
		)
		(property "Footprint" "antmicro-footprints:R_0402_1005Metric"
			(at 0 0 90)
			(layer "F.Fab")
			(hide yes)
			(effects
				(font
					(size 1.27 1.27)
					(thickness 0.15)
				)
			)
		)
		(property "Datasheet" "https://www.bourns.com/docs/product-datasheets/cr.pdf"
			(at 0 0 90)
			(layer "F.Fab")
			(hide yes)
			(effects
				(font
					(size 1.27 1.27)
					(thickness 0.15)
				)
			)
		)
		(property "Description" "SMD Chip Resistor, 2.7 kohm, ± 1%, 63 mW, 0402 [1005 Metric], Thick Film, General Purpose"
			(at 0 0 90)
			(layer "F.Fab")
			(hide yes)
			(effects
				(font
					(size 1.27 1.27)
					(thickness 0.15)
				)
			)
		)
		(property "Author" "Antmicro"
			(at 167.09 31.75 0)
			(layer "F.Fab")
			(hide yes)
			(effects
				(font
					(size 1 1)
					(thickness 0.15)
				)
			)
		)
		(property "License" "Apache-2.0"
			(at 167.09 31.75 0)
			(layer "F.Fab")
			(hide yes)
			(effects
				(font
					(size 1 1)
					(thickness 0.15)
				)
			)
		)
		(property "MPN" "CR0402-FX-2701GLF"
			(at 167.09 31.75 0)
			(layer "F.Fab")
			(hide yes)
			(effects
				(font
					(size 1 1)
					(thickness 0.15)
				)
			)
		)
		(property "Manufacturer" "Bourns"
			(at 167.09 31.75 0)
			(layer "F.Fab")
			(hide yes)
			(effects
				(font
					(size 1 1)
					(thickness 0.15)
				)
			)
		)
		(property "Tolerance" "1%"
			(at 167.09 31.75 0)
			(layer "F.Fab")
			(hide yes)
			(effects
				(font
					(size 1 1)
					(thickness 0.15)
				)
			)
		)
		(property "Val" "2k7"
			(at 167.09 31.75 0)
			(layer "F.Fab")
			(hide yes)
			(effects
				(font
					(size 1 1)
					(thickness 0.15)
				)
			)
		)
		(sheetname "Supply")
		(sheetfile "supply.kicad_sch")
		(attr smd)
		(fp_rect
			(start -0.925 -0.47)
			(end 0.925 0.47)
			(stroke
				(width 0.05)
				(type default)
			)
			(fill none)
			(layer "F.CrtYd")
		)
		(fp_rect
			(start -0.5 -0.25)
			(end 0.5 0.25)
			(stroke
				(width 0.15)
				(type solid)
			)
			(fill none)
			(layer "F.Fab")
		)
		(fp_text user "${REFERENCE}"
			(at -0.95 3.168 90)
			(layer "F.Fab")
			(hide yes)
			(effects
				(font
					(size 0.7 0.7)
					(thickness 0.15)
				)
				(justify left bottom)
			)
		)
		(fp_text user "Author: Antmicro"
			(at -0.95 4.169 90)
			(layer "F.Fab")
			(hide yes)
			(effects
				(font
					(size 0.7 0.7)
					(thickness 0.15)
				)
				(justify left bottom)
			)
		)
		(fp_text user "License: Apache-2.0"
			(at -0.95 5.169 90)
			(layer "F.Fab")
			(hide yes)
			(effects
				(font
					(size 0.7 0.7)
					(thickness 0.15)
				)
				(justify left bottom)
			)
		)
		(pad "1" smd roundrect
			(at -0.48 0 90)
			(size 0.59 0.64)
			(layers "F.Cu" "F.Paste" "F.Mask")
			(roundrect_rratio 0.25)
			(net 1 "GND")
			(pintype "passive")
		)
		(pad "2" smd roundrect
			(at 0.48 0 90)
			(size 0.59 0.64)
			(layers "F.Cu" "F.Paste" "F.Mask")
			(roundrect_rratio 0.25)
			(net 712 "/Supply/5V_EN")
			(pintype "passive")
		)
	)
	(footprint "antmicro-footprints:USON-10_2.5x1mm_P0.5mm"
		(layer "F.Cu")
		(at 113.55 116.178749 90)
		(descr "USON-10 2.5x1mm_ Pitch 0.5mm")
		(tags "USON-10 2.5x1mm Pitch 0.5mm")
		(property "Reference" "U21"
			(at 0.878749 -1.05 180)
			(layer "F.SilkS")
			(effects
				(font
					(size 0.7 0.7)
					(thickness 0.15)
				)
				(justify left bottom)
			)
		)
		(property "Value" "TPD4E05U06QDQARQ1"
			(at 0.018 2.499 90)
			(layer "F.Fab")
			(effects
				(font
					(size 0.7 0.7)
					(thickness 0.15)
				)
				(justify left bottom)
			)
		)
		(property "Footprint" "antmicro-footprints:USON-10_2.5x1mm_P0.5mm"
			(at 0 0 90)
			(layer "F.Fab")
			(hide yes)
			(effects
				(font
					(size 1.27 1.27)
					(thickness 0.15)
				)
			)
		)
		(property "Datasheet" "https://www.ti.com/lit/ds/symlink/tpd4e05u06-q1.pdf?HQS=dis-mous-null-mousermode-dsf-pf-null-wwe&ts=1663591265741&ref_url=https%253A%252F%252Fwww.mouser.com%252F"
			(at 0 0 90)
			(layer "F.Fab")
			(hide yes)
			(effects
				(font
					(size 1.27 1.27)
					(thickness 0.15)
				)
			)
		)
		(property "Author" "Antmicro"
			(at 229.728749 2.628749 0)
			(layer "F.Fab")
			(hide yes)
			(effects
				(font
					(size 1 1)
					(thickness 0.15)
				)
			)
		)
		(property "License" "Apache-2.0"
			(at 229.728749 2.628749 0)
			(layer "F.Fab")
			(hide yes)
			(effects
				(font
					(size 1 1)
					(thickness 0.15)
				)
			)
		)
		(property "MPN" "TPD4E05U06QDQARQ1"
			(at 229.728749 2.628749 0)
			(layer "F.Fab")
			(hide yes)
			(effects
				(font
					(size 1 1)
					(thickness 0.15)
				)
			)
		)
		(property "Manufacturer" "Texas Instruments"
			(at 229.728749 2.628749 0)
			(layer "F.Fab")
			(hide yes)
			(effects
				(font
					(size 1 1)
					(thickness 0.15)
				)
			)
		)
		(sheetname "USB3")
		(sheetfile "usb3.kicad_sch")
		(attr smd)
		(fp_line
			(start 0.498 -1.401)
			(end -0.5 -1.401)
			(stroke
				(width 0.15)
				(type solid)
			)
			(layer "F.SilkS")
		)
		(fp_line
			(start 0.498 1.398)
			(end -0.5 1.398)
			(stroke
				(width 0.15)
				(type solid)
			)
			(layer "F.SilkS")
		)
		(fp_circle
			(center -0.68 -1.27)
			(end -0.63 -1.27)
			(stroke
				(width 0.15)
				(type solid)
			)
			(fill solid)
			(layer "F.SilkS")
		)
		(fp_rect
			(start -0.8 -1.5)
			(end 0.8 1.499)
			(stroke
				(width 0.05)
				(type solid)
			)
			(fill none)
			(layer "F.CrtYd")
		)
		(fp_line
			(start 0.498 -1.25)
			(end -0.25 -1.25)
			(stroke
				(width 0.15)
				(type solid)
			)
			(layer "F.Fab")
		)
		(fp_line
			(start 0.498 -1.25)
			(end 0.498 1.249)
			(stroke
				(width 0.15)
				(type solid)
			)
			(layer "F.Fab")
		)
		(fp_line
			(start -0.25 -1.25)
			(end -0.5 -1)
			(stroke
				(width 0.15)
				(type solid)
			)
			(layer "F.Fab")
		)
		(fp_line
			(start -0.5 -1)
			(end -0.5 1.249)
			(stroke
				(width 0.15)
				(type solid)
			)
			(layer "F.Fab")
		)
		(fp_line
			(start -0.5 1.249)
			(end 0.498 1.249)
			(stroke
				(width 0.15)
				(type solid)
			)
			(layer "F.Fab")
		)
		(fp_text user "${REFERENCE}"
			(at -0.802 4.498 90)
			(layer "F.Fab")
			(hide yes)
			(effects
				(font
					(size 0.7 0.7)
					(thickness 0.15)
				)
				(justify left bottom)
			)
		)
		(fp_text user "Author: Antmicro"
			(at -0.802 5.7 90)
			(layer "F.Fab")
			(hide yes)
			(effects
				(font
					(size 0.7 0.7)
					(thickness 0.15)
				)
				(justify left bottom)
			)
		)
		(fp_text user "License: Apache-2.0"
			(at -0.802 6.9 90)
			(layer "F.Fab")
			(hide yes)
			(effects
				(font
					(size 0.7 0.7)
					(thickness 0.15)
				)
				(justify left bottom)
			)
		)
		(pad "1" smd roundrect
			(at -0.387 -1)
			(size 0.25 0.55)
			(layers "F.Cu" "F.Paste" "F.Mask")
			(roundrect_rratio 0.25)
			(net 282 "/USB3/USBC1_CC1")
			(pintype "passive")
		)
		(pad "2" smd roundrect
			(at -0.387 -0.5)
			(size 0.25 0.55)
			(layers "F.Cu" "F.Paste" "F.Mask")
			(roundrect_rratio 0.25)
			(net 433 "USB0_D_P")
			(pintype "passive")
		)
		(pad "3" smd roundrect
			(at -0.387 0)
			(size 0.4 0.55)
			(layers "F.Cu" "F.Paste" "F.Mask")
			(roundrect_rratio 0.25)
			(net 1 "GND")
			(pintype "power_in")
		)
		(pad "4" smd roundrect
			(at -0.387 0.498)
			(size 0.25 0.55)
			(layers "F.Cu" "F.Paste" "F.Mask")
			(roundrect_rratio 0.25)
			(net 40 "USB0_D_N")
			(pintype "passive")
		)
		(pad "5" smd roundrect
			(at -0.387 0.998)
			(size 0.25 0.55)
			(layers "F.Cu" "F.Paste" "F.Mask")
			(roundrect_rratio 0.25)
			(net 283 "/USB3/USBC1_CC2")
			(pintype "passive")
		)
		(pad "6" smd roundrect
			(at 0.385 0.998)
			(size 0.25 0.55)
			(layers "F.Cu" "F.Paste" "F.Mask")
			(roundrect_rratio 0.25)
			(net 283 "/USB3/USBC1_CC2")
			(pintype "passive")
		)
		(pad "7" smd roundrect
			(at 0.385 0.498)
			(size 0.25 0.55)
			(layers "F.Cu" "F.Paste" "F.Mask")
			(roundrect_rratio 0.25)
			(net 40 "USB0_D_N")
			(pintype "passive")
		)
		(pad "8" smd roundrect
			(at 0.385 0)
			(size 0.4 0.55)
			(layers "F.Cu" "F.Paste" "F.Mask")
			(roundrect_rratio 0.25)
			(net 1 "GND")
			(pintype "passive")
		)
		(pad "9" smd roundrect
			(at 0.385 -0.5)
			(size 0.25 0.55)
			(layers "F.Cu" "F.Paste" "F.Mask")
			(roundrect_rratio 0.25)
			(net 433 "USB0_D_P")
			(pintype "passive")
		)
		(pad "10" smd roundrect
			(at 0.385 -1)
			(size 0.25 0.55)
			(layers "F.Cu" "F.Paste" "F.Mask")
			(roundrect_rratio 0.25)
			(net 282 "/USB3/USBC1_CC1")
			(pintype "passive")
		)
	)
	(footprint "antmicro-footprints:Mech_M2_2242_H2.5mm"
		(layer "F.Cu")
		(at 79.25 95.15 90)
		(property "Reference" "A2"
			(at -0.001 -12.11 90)
			(layer "F.SilkS")
			(hide yes)
			(effects
				(font
					(size 0.7 0.7)
					(thickness 0.15)
				)
				(justify right bottom)
			)
		)
		(property "Value" "Mech_M2_2242_H2.5mm"
			(at -0.001 6.857 90)
			(layer "F.Fab")
			(effects
				(font
					(size 0.7 0.7)
					(thickness 0.15)
				)
				(justify right bottom)
			)
		)
		(property "Footprint" "antmicro-footprints:Mech_M2_2242_H2.5mm"
			(at 0 0 90)
			(layer "F.Fab")
			(hide yes)
			(effects
				(font
					(size 1.27 1.27)
					(thickness 0.15)
				)
			)
		)
		(property "MPN" ""
			(at 0 0 90)
			(unlocked yes)
			(layer "F.Fab")
			(hide yes)
			(effects
				(font
					(size 1 1)
					(thickness 0.15)
				)
			)
		)
		(property "Manufacturer" ""
			(at 0 0 90)
			(unlocked yes)
			(layer "F.Fab")
			(hide yes)
			(effects
				(font
					(size 1 1)
					(thickness 0.15)
				)
			)
		)
		(property "Author" "Antmicro"
			(at 0 0 90)
			(unlocked yes)
			(layer "F.Fab")
			(hide yes)
			(effects
				(font
					(size 1 1)
					(thickness 0.15)
				)
			)
		)
		(property "License" "Apache-2.0"
			(at 0 0 90)
			(unlocked yes)
			(layer "F.Fab")
			(hide yes)
			(effects
				(font
					(size 1 1)
					(thickness 0.15)
				)
			)
		)
		(sheetname "M.2")
		(sheetfile "m-2.kicad_sch")
		(attr through_hole exclude_from_pos_files exclude_from_bom allow_missing_courtyard
			dnp
		)
		(fp_text user "${REFERENCE}"
			(at -11 66.248 90)
			(layer "F.Fab")
			(hide yes)
			(effects
				(font
					(size 0.7 0.7)
					(thickness 0.15)
				)
				(justify left bottom)
			)
		)
		(fp_text user "Author: Antmicro"
			(at -11 67.45 90)
			(layer "F.Fab")
			(hide yes)
			(effects
				(font
					(size 0.7 0.7)
					(thickness 0.15)
				)
				(justify left bottom)
			)
		)
		(fp_text user "License: Apache-2.0"
			(at -11 68.65 90)
			(layer "F.Fab")
			(hide yes)
			(effects
				(font
					(size 0.7 0.7)
					(thickness 0.15)
				)
				(justify left bottom)
			)
		)
	)
)
